(kicad_pcb
	(version 20260206)
	(generator "pcbnew")
	(generator_version "10.0")
	(general
		(thickness 1.6)
		(legacy_teardrops no)
	)
	(paper "A4")
	(title_block
		(title "12092022_DA0F0TMDCD0_F0T_Management_Board_D_brd_V3_OCP.brd")
		(comment 1 "Grand Teton / footprints 1228-1232 of 1440")
	)
	(layers
		(0 "F.Cu" signal "TOP")
		(4 "In1.Cu" signal "GND")
		(6 "In2.Cu" signal "IN1")
		(8 "In3.Cu" signal "GND1")
		(10 "In4.Cu" signal "IN2")
		(12 "In5.Cu" signal "VCC")
		(14 "In6.Cu" signal "VCC1")
		(16 "In7.Cu" signal "IN3")
		(18 "In8.Cu" signal "GND2")
		(20 "In9.Cu" signal "IN4")
		(22 "In10.Cu" signal "GND3")
		(2 "B.Cu" signal "BOTTOM")
		(9 "F.Adhes" user "F.Adhesive")
		(11 "B.Adhes" user "B.Adhesive")
		(13 "F.Paste" user "Package Geometry/Pastemask Top")
		(15 "B.Paste" user "Package Geometry/Pastemask Bottom")
		(5 "F.SilkS" user "Ref Des/Silkscreen Top")
		(7 "B.SilkS" user "Ref Des/Silkscreen Bottom")
		(1 "F.Mask" user "Board Geometry/Soldermask Top")
		(3 "B.Mask" user "Board Geometry/Soldermask Bottom")
		(17 "Dwgs.User" user "User.Drawings")
		(19 "Cmts.User" user "User.Comments")
		(21 "Eco1.User" user "User.Eco1")
		(23 "Eco2.User" user "User.Eco2")
		(25 "Edge.Cuts" user "Board Geometry/Outline")
		(27 "Margin" user)
		(31 "F.CrtYd" user "Package Geometry/Place Bound Top")
		(29 "B.CrtYd" user "Package Geometry/Place Bound Bottom")
		(35 "F.Fab" user "Ref Des/Assembly Top")
		(33 "B.Fab" user "Ref Des/Assembly Bottom")
	)
	(footprint ""
		(layer "B.Cu")
		(at 41.1988 -37.338 180)
		(property "Reference" "R760"
			(at 0 0 0)
			(layer "B.SilkS")
			(hide yes)
			(effects
				(font
					(size 1.27 1.27)
				)
				(justify mirror)
			)
		)
		(property "Value" ""
			(at 0 0 0)
			(layer "B.Fab")
			(effects
				(font
					(size 1.27 1.27)
				)
				(justify mirror)
			)
		)
		(duplicate_pad_numbers_are_jumpers no)
		(fp_line
			(start 0.7874 0.4064)
			(end 0.7874 -0.4064)
			(stroke
				(width 0.1524)
				(type default)
			)
			(layer "B.SilkS")
		)
		(fp_line
			(start 0.7874 -0.4064)
			(end -0.7874 -0.4064)
			(stroke
				(width 0.1524)
				(type default)
			)
			(layer "B.SilkS")
		)
		(fp_line
			(start -0.7874 0.4064)
			(end 0.7874 0.4064)
			(stroke
				(width 0.1524)
				(type default)
			)
			(layer "B.SilkS")
		)
		(fp_line
			(start -0.7874 -0.4064)
			(end -0.7874 0.4064)
			(stroke
				(width 0.1524)
				(type default)
			)
			(layer "B.SilkS")
		)
		(fp_line
			(start 0.67945 0.3048)
			(end 0.67945 -0.305054)
			(stroke
				(width 0.1)
				(type default)
			)
			(layer "B.Fab")
		)
		(fp_line
			(start 0.67945 -0.305054)
			(end 0.12065 -0.305054)
			(stroke
				(width 0.1)
				(type default)
			)
			(layer "B.Fab")
		)
		(fp_line
			(start 0.12065 0.3048)
			(end 0.67945 0.3048)
			(stroke
				(width 0.1)
				(type default)
			)
			(layer "B.Fab")
		)
		(fp_line
			(start 0.12065 0.2794)
			(end 0.12065 0.3048)
			(stroke
				(width 0.1)
				(type default)
			)
			(layer "B.Fab")
		)
		(fp_line
			(start 0.12065 -0.2794)
			(end -0.12065 -0.2794)
			(stroke
				(width 0.1)
				(type default)
			)
			(layer "B.Fab")
		)
		(fp_line
			(start 0.12065 -0.305054)
			(end 0.12065 -0.2794)
			(stroke
				(width 0.1)
				(type default)
			)
			(layer "B.Fab")
		)
		(fp_line
			(start -0.120396 0.3048)
			(end -0.120396 0.2794)
			(stroke
				(width 0.1)
				(type default)
			)
			(layer "B.Fab")
		)
		(fp_line
			(start -0.120396 0.2794)
			(end 0.12065 0.2794)
			(stroke
				(width 0.1)
				(type default)
			)
			(layer "B.Fab")
		)
		(fp_line
			(start -0.12065 -0.2794)
			(end -0.12065 -0.3048)
			(stroke
				(width 0.1)
				(type default)
			)
			(layer "B.Fab")
		)
		(fp_line
			(start -0.12065 -0.3048)
			(end -0.67945 -0.3048)
			(stroke
				(width 0.1)
				(type default)
			)
			(layer "B.Fab")
		)
		(fp_line
			(start -0.67945 0.3048)
			(end -0.120396 0.3048)
			(stroke
				(width 0.1)
				(type default)
			)
			(layer "B.Fab")
		)
		(fp_line
			(start -0.67945 -0.3048)
			(end -0.67945 0.3048)
			(stroke
				(width 0.1)
				(type default)
			)
			(layer "B.Fab")
		)
		(pad "1" smd circle
			(at 0.40005 0)
			(size 0 0)
			(layers "B.Cu" "B.Mask" "B.Paste")
			(net "FM_BMC_CRASHLOG_TRIG_N")
		)
		(pad "2" smd circle
			(at -0.40005 0)
			(size 0 0)
			(layers "B.Cu" "B.Mask" "B.Paste")
			(net "FM_BMC_CRASHLOG_TRIG_R1_N")
		)
	)
	(footprint ""
		(layer "B.Cu")
		(at 68.58 -14.478)
		(property "Reference" "R883"
			(at 0 0 0)
			(layer "B.SilkS")
			(hide yes)
			(effects
				(font
					(size 1.27 1.27)
				)
				(justify mirror)
			)
		)
		(property "Value" ""
			(at 0 0 0)
			(layer "B.Fab")
			(effects
				(font
					(size 1.27 1.27)
				)
				(justify mirror)
			)
		)
		(duplicate_pad_numbers_are_jumpers no)
		(fp_line
			(start -0.7874 -0.4064)
			(end -0.7874 0.4064)
			(stroke
				(width 0.1524)
				(type default)
			)
			(layer "B.SilkS")
		)
		(fp_line
			(start -0.7874 0.4064)
			(end 0.7874 0.4064)
			(stroke
				(width 0.1524)
				(type default)
			)
			(layer "B.SilkS")
		)
		(fp_line
			(start 0.7874 -0.4064)
			(end -0.7874 -0.4064)
			(stroke
				(width 0.1524)
				(type default)
			)
			(layer "B.SilkS")
		)
		(fp_line
			(start 0.7874 0.4064)
			(end 0.7874 -0.4064)
			(stroke
				(width 0.1524)
				(type default)
			)
			(layer "B.SilkS")
		)
		(fp_line
			(start -0.67945 -0.3048)
			(end -0.67945 0.3048)
			(stroke
				(width 0.1)
				(type default)
			)
			(layer "B.Fab")
		)
		(fp_line
			(start -0.67945 0.3048)
			(end -0.120396 0.3048)
			(stroke
				(width 0.1)
				(type default)
			)
			(layer "B.Fab")
		)
		(fp_line
			(start -0.12065 -0.3048)
			(end -0.67945 -0.3048)
			(stroke
				(width 0.1)
				(type default)
			)
			(layer "B.Fab")
		)
		(fp_line
			(start -0.12065 -0.2794)
			(end -0.12065 -0.3048)
			(stroke
				(width 0.1)
				(type default)
			)
			(layer "B.Fab")
		)
		(fp_line
			(start -0.120396 0.2794)
			(end 0.12065 0.2794)
			(stroke
				(width 0.1)
				(type default)
			)
			(layer "B.Fab")
		)
		(fp_line
			(start -0.120396 0.3048)
			(end -0.120396 0.2794)
			(stroke
				(width 0.1)
				(type default)
			)
			(layer "B.Fab")
		)
		(fp_line
			(start 0.12065 -0.305054)
			(end 0.12065 -0.2794)
			(stroke
				(width 0.1)
				(type default)
			)
			(layer "B.Fab")
		)
		(fp_line
			(start 0.12065 -0.2794)
			(end -0.12065 -0.2794)
			(stroke
				(width 0.1)
				(type default)
			)
			(layer "B.Fab")
		)
		(fp_line
			(start 0.12065 0.2794)
			(end 0.12065 0.3048)
			(stroke
				(width 0.1)
				(type default)
			)
			(layer "B.Fab")
		)
		(fp_line
			(start 0.12065 0.3048)
			(end 0.67945 0.3048)
			(stroke
				(width 0.1)
				(type default)
			)
			(layer "B.Fab")
		)
		(fp_line
			(start 0.67945 -0.305054)
			(end 0.12065 -0.305054)
			(stroke
				(width 0.1)
				(type default)
			)
			(layer "B.Fab")
		)
		(fp_line
			(start 0.67945 0.3048)
			(end 0.67945 -0.305054)
			(stroke
				(width 0.1)
				(type default)
			)
			(layer "B.Fab")
		)
		(pad "1" smd circle
			(at 0.40005 0 180)
			(size 0 0)
			(layers "B.Cu" "B.Mask" "B.Paste")
			(net "P3V3_AUX")
		)
		(pad "2" smd circle
			(at -0.40005 0 180)
			(size 0 0)
			(layers "B.Cu" "B.Mask" "B.Paste")
			(net "REAR_AC_PWR_BMC_BTN_N")
		)
	)
	(footprint ""
		(layer "B.Cu")
		(at 68.95338 -55.353966 90)
		(property "Reference" "C47"
			(at 0 0 90)
			(layer "B.SilkS")
			(hide yes)
			(effects
				(font
					(size 1.27 1.27)
				)
				(justify mirror)
			)
		)
		(property "Value" ""
			(at 0 0 90)
			(layer "B.Fab")
			(effects
				(font
					(size 1.27 1.27)
				)
				(justify mirror)
			)
		)
		(duplicate_pad_numbers_are_jumpers no)
		(fp_line
			(start 0.7874 -0.4064)
			(end -0.7874 -0.4064)
			(stroke
				(width 0.1524)
				(type default)
			)
			(layer "B.SilkS")
		)
		(fp_line
			(start -0.7874 -0.4064)
			(end -0.7874 0.4064)
			(stroke
				(width 0.1524)
				(type default)
			)
			(layer "B.SilkS")
		)
		(fp_line
			(start 0.7874 0.4064)
			(end 0.7874 -0.4064)
			(stroke
				(width 0.1524)
				(type default)
			)
			(layer "B.SilkS")
		)
		(fp_line
			(start -0.7874 0.4064)
			(end 0.7874 0.4064)
			(stroke
				(width 0.1524)
				(type default)
			)
			(layer "B.SilkS")
		)
		(fp_line
			(start 0.67945 -0.305054)
			(end 0.12065 -0.305054)
			(stroke
				(width 0.1)
				(type default)
			)
			(layer "B.Fab")
		)
		(fp_line
			(start 0.12065 -0.305054)
			(end 0.12065 -0.2794)
			(stroke
				(width 0.1)
				(type default)
			)
			(layer "B.Fab")
		)
		(fp_line
			(start -0.12065 -0.3048)
			(end -0.67945 -0.3048)
			(stroke
				(width 0.1)
				(type default)
			)
			(layer "B.Fab")
		)
		(fp_line
			(start -0.67945 -0.3048)
			(end -0.67945 0.3048)
			(stroke
				(width 0.1)
				(type default)
			)
			(layer "B.Fab")
		)
		(fp_line
			(start 0.12065 -0.2794)
			(end -0.12065 -0.2794)
			(stroke
				(width 0.1)
				(type default)
			)
			(layer "B.Fab")
		)
		(fp_line
			(start -0.12065 -0.2794)
			(end -0.12065 -0.3048)
			(stroke
				(width 0.1)
				(type default)
			)
			(layer "B.Fab")
		)
		(fp_line
			(start 0.12065 0.2794)
			(end 0.12065 0.3048)
			(stroke
				(width 0.1)
				(type default)
			)
			(layer "B.Fab")
		)
		(fp_line
			(start -0.120396 0.2794)
			(end 0.12065 0.2794)
			(stroke
				(width 0.1)
				(type default)
			)
			(layer "B.Fab")
		)
		(fp_line
			(start 0.67945 0.3048)
			(end 0.67945 -0.305054)
			(stroke
				(width 0.1)
				(type default)
			)
			(layer "B.Fab")
		)
		(fp_line
			(start 0.12065 0.3048)
			(end 0.67945 0.3048)
			(stroke
				(width 0.1)
				(type default)
			)
			(layer "B.Fab")
		)
		(fp_line
			(start -0.120396 0.3048)
			(end -0.120396 0.2794)
			(stroke
				(width 0.1)
				(type default)
			)
			(layer "B.Fab")
		)
		(fp_line
			(start -0.67945 0.3048)
			(end -0.120396 0.3048)
			(stroke
				(width 0.1)
				(type default)
			)
			(layer "B.Fab")
		)
		(pad "1" smd circle
			(at 0.40005 0 270)
			(size 0 0)
			(layers "B.Cu" "B.Mask" "B.Paste")
			(net "P1V0_STBY_RC_VCC10A")
		)
		(pad "2" smd circle
			(at -0.40005 0 270)
			(size 0 0)
			(layers "B.Cu" "B.Mask" "B.Paste")
			(net "GND")
		)
	)
	(footprint ""
		(layer "B.Cu")
		(at 24.003 -101.981 -90)
		(property "Reference" "R621"
			(at 0 0 90)
			(layer "B.SilkS")
			(hide yes)
			(effects
				(font
					(size 1.27 1.27)
				)
				(justify mirror)
			)
		)
		(property "Value" ""
			(at 0 0 90)
			(layer "B.Fab")
			(effects
				(font
					(size 1.27 1.27)
				)
				(justify mirror)
			)
		)
		(duplicate_pad_numbers_are_jumpers no)
		(fp_line
			(start -0.7874 0.4064)
			(end 0.7874 0.4064)
			(stroke
				(width 0.1524)
				(type default)
			)
			(layer "B.SilkS")
		)
		(fp_line
			(start 0.7874 0.4064)
			(end 0.7874 -0.4064)
			(stroke
				(width 0.1524)
				(type default)
			)
			(layer "B.SilkS")
		)
		(fp_line
			(start -0.7874 -0.4064)
			(end -0.7874 0.4064)
			(stroke
				(width 0.1524)
				(type default)
			)
			(layer "B.SilkS")
		)
		(fp_line
			(start 0.7874 -0.4064)
			(end -0.7874 -0.4064)
			(stroke
				(width 0.1524)
				(type default)
			)
			(layer "B.SilkS")
		)
		(fp_line
			(start -0.67945 0.3048)
			(end -0.120396 0.3048)
			(stroke
				(width 0.1)
				(type default)
			)
			(layer "B.Fab")
		)
		(fp_line
			(start -0.120396 0.3048)
			(end -0.120396 0.2794)
			(stroke
				(width 0.1)
				(type default)
			)
			(layer "B.Fab")
		)
		(fp_line
			(start 0.12065 0.3048)
			(end 0.67945 0.3048)
			(stroke
				(width 0.1)
				(type default)
			)
			(layer "B.Fab")
		)
		(fp_line
			(start 0.67945 0.3048)
			(end 0.67945 -0.305054)
			(stroke
				(width 0.1)
				(type default)
			)
			(layer "B.Fab")
		)
		(fp_line
			(start -0.120396 0.2794)
			(end 0.12065 0.2794)
			(stroke
				(width 0.1)
				(type default)
			)
			(layer "B.Fab")
		)
		(fp_line
			(start 0.12065 0.2794)
			(end 0.12065 0.3048)
			(stroke
				(width 0.1)
				(type default)
			)
			(layer "B.Fab")
		)
		(fp_line
			(start -0.12065 -0.2794)
			(end -0.12065 -0.3048)
			(stroke
				(width 0.1)
				(type default)
			)
			(layer "B.Fab")
		)
		(fp_line
			(start 0.12065 -0.2794)
			(end -0.12065 -0.2794)
			(stroke
				(width 0.1)
				(type default)
			)
			(layer "B.Fab")
		)
		(fp_line
			(start -0.67945 -0.3048)
			(end -0.67945 0.3048)
			(stroke
				(width 0.1)
				(type default)
			)
			(layer "B.Fab")
		)
		(fp_line
			(start -0.12065 -0.3048)
			(end -0.67945 -0.3048)
			(stroke
				(width 0.1)
				(type default)
			)
			(layer "B.Fab")
		)
		(fp_line
			(start 0.12065 -0.305054)
			(end 0.12065 -0.2794)
			(stroke
				(width 0.1)
				(type default)
			)
			(layer "B.Fab")
		)
		(fp_line
			(start 0.67945 -0.305054)
			(end 0.12065 -0.305054)
			(stroke
				(width 0.1)
				(type default)
			)
			(layer "B.Fab")
		)
		(pad "1" smd circle
			(at 0.40005 0 90)
			(size 0 0)
			(layers "B.Cu" "B.Mask" "B.Paste")
			(net "P3V3_AUX")
		)
		(pad "2" smd circle
			(at -0.40005 0 90)
			(size 0 0)
			(layers "B.Cu" "B.Mask" "B.Paste")
			(net "FM_P12V_HSC_ENABLE")
		)
	)
	(footprint ""
		(layer "B.Cu")
		(at 114.554 -77.216 -90)
		(property "Reference" "X8"
			(at 1.94437 1.3462 0)
			(unlocked yes)
			(layer "B.SilkS")
			(effects
				(font
					(size 0.7874 0.5842)
					(thickness 0.1524)
				)
				(justify left mirror)
			)
		)
		(property "Value" ""
			(at 0 0 90)
			(layer "B.Fab")
			(effects
				(font
					(size 1.27 1.27)
				)
				(justify mirror)
			)
		)
		(property "Device Type" "TP_TDR_4P_FTS_TH-TP_TDR_4P_DIPA"
			(at -1.30175 1.27 180)
			(unlocked yes)
			(layer "B.Fab")
			(hide yes)
			(effects
				(font
					(size 0.635 0.4064)
					(thickness 0.1524)
				)
				(justify mirror)
			)
		)
		(property "User Part Number" "N_A"
			(at -1.30175 1.27 180)
			(unlocked yes)
			(layer "Cmts.User")
			(hide yes)
			(effects
				(font
					(size 0.635 0.4064)
					(thickness 0.1524)
				)
				(justify mirror)
			)
		)
		(duplicate_pad_numbers_are_jumpers no)
		(fp_line
			(start -2.54 3.81)
			(end -2.54 3.6703)
			(stroke
				(width 0.1524)
				(type default)
			)
			(layer "B.SilkS")
		)
		(fp_line
			(start 0 3.81)
			(end -2.54 3.81)
			(stroke
				(width 0.1524)
				(type default)
			)
			(layer "B.SilkS")
		)
		(fp_line
			(start 0 3.175)
			(end 0 3.81)
			(stroke
				(width 0.1524)
				(type default)
			)
			(layer "B.SilkS")
		)
		(fp_line
			(start -2.54 1.4097)
			(end -2.54 1.1303)
			(stroke
				(width 0.1524)
				(type default)
			)
			(layer "B.SilkS")
		)
		(fp_line
			(start 0 0.635)
			(end 0 1.905)
			(stroke
				(width 0.1524)
				(type default)
			)
			(layer "B.SilkS")
		)
		(fp_line
			(start -2.54 -1.1303)
			(end -2.54 -1.27)
			(stroke
				(width 0.1524)
				(type default)
			)
			(layer "B.SilkS")
		)
		(fp_line
			(start -2.54 -1.27)
			(end 0 -1.27)
			(stroke
				(width 0.1524)
				(type default)
			)
			(layer "B.SilkS")
		)
		(fp_line
			(start 0 -1.27)
			(end 0 -0.635)
			(stroke
				(width 0.1524)
				(type default)
			)
			(layer "B.SilkS")
		)
		(fp_poly
			(pts
				(xy 0.761746 0) (xy 2.285746 -0.762) (xy 2.285746 0.762)
			)
			(stroke
				(width 0)
				(type default)
			)
			(fill yes)
			(layer "B.SilkS")
		)
		(fp_line
			(start -2.54 3.81)
			(end -2.54 -1.27)
			(stroke
				(width 0.1)
				(type default)
			)
			(layer "B.Fab")
		)
		(fp_line
			(start 0 3.81)
			(end -2.54 3.81)
			(stroke
				(width 0.1)
				(type default)
			)
			(layer "B.Fab")
		)
		(fp_line
			(start -2.54 -1.27)
			(end 0 -1.27)
			(stroke
				(width 0.1)
				(type default)
			)
			(layer "B.Fab")
		)
		(fp_line
			(start 0 -1.27)
			(end 0 3.81)
			(stroke
				(width 0.1)
				(type default)
			)
			(layer "B.Fab")
		)
		(fp_poly
			(pts
				(xy 0.761746 0) (xy 2.285746 -0.762) (xy 2.285746 0.762)
			)
			(stroke
				(width 0)
				(type default)
			)
			(fill yes)
			(layer "B.Fab")
		)
		(pad "1" thru_hole circle
			(at 0 0 90)
			(size 1.0033 1.0033)
			(drill 0.249936)
			(layers "*.Cu" "*.Mask")
			(remove_unused_layers no)
			(net "TDR_DIFF_85_IN1_DN")
			(clearance 0.10795)
			(padstack
				(mode front_inner_back)
				(layer "Inner"
					(shape circle)
					(size 0.8001 0.8001)
					(clearance 0.1524)
				)
				(layer "B.Cu"
					(shape circle)
					(size 1.0033 1.0033)
					(thermal_gap 0.10795)
					(clearance 0.10795)
				)
			)
		)
		(pad "2" thru_hole circle
			(at -2.54 0 90)
			(size 1.9939 1.9939)
			(drill 0.249936)
			(layers "*.Cu" "*.Mask")
			(remove_unused_layers no)
			(net "GND_P1")
			(clearance 0.10795)
			(padstack
				(mode front_inner_back)
				(layer "Inner"
					(shape circle)
					(size 0.8001 0.8001)
					(clearance 0.1524)
				)
				(layer "B.Cu"
					(shape circle)
					(size 1.9939 1.9939)
					(thermal_gap 0.10795)
					(clearance 0.10795)
				)
			)
		)
		(pad "3" thru_hole circle
			(at -2.54 2.54 90)
			(size 1.9939 1.9939)
			(drill 0.249936)
			(layers "*.Cu" "*.Mask")
			(remove_unused_layers no)
			(net "GND_P1")
			(clearance 0.10795)
			(padstack
				(mode front_inner_back)
				(layer "Inner"
					(shape circle)
					(size 0.8001 0.8001)
					(clearance 0.1524)
				)
				(layer "B.Cu"
					(shape circle)
					(size 1.9939 1.9939)
					(thermal_gap 0.10795)
					(clearance 0.10795)
				)
			)
		)
		(pad "4" thru_hole circle
			(at 0 2.54 90)
			(size 1.0033 1.0033)
			(drill 0.249936)
			(layers "*.Cu" "*.Mask")
			(remove_unused_layers no)
			(net "TDR_DIFF_85_IN1_DP")
			(clearance 0.10795)
			(padstack
				(mode front_inner_back)
				(layer "Inner"
					(shape circle)
					(size 0.8001 0.8001)
					(clearance 0.1524)
				)
				(layer "B.Cu"
					(shape circle)
					(size 1.0033 1.0033)
					(thermal_gap 0.10795)
					(clearance 0.10795)
				)
			)
		)
	)
)
